(kicad_pcb
	(version 20241229)
	(generator "pcbnew")
	(generator_version "9.0")
	(general
		(thickness 1.62)
		(legacy_teardrops no)
	)
	(paper "A3")
	(title_block
		(title "COM Express 7 Baseboard")
		(date "2025-02-04")
		(rev "1.1.2")
		(company "Antmicro Ltd")
		(comment 1 "www.antmicro.com")
		(comment 9 "footprints 602-605 of 802")
	)
	(layers
		(0 "F.Cu" signal)
		(4 "In1.Cu" signal)
		(6 "In2.Cu" signal)
		(8 "In3.Cu" signal)
		(10 "In4.Cu" signal)
		(12 "In5.Cu" signal)
		(14 "In6.Cu" signal)
		(2 "B.Cu" signal)
		(9 "F.Adhes" user "F.Adhesive")
		(11 "B.Adhes" user "B.Adhesive")
		(13 "F.Paste" user)
		(15 "B.Paste" user)
		(5 "F.SilkS" user "F.Silkscreen")
		(7 "B.SilkS" user "B.Silkscreen")
		(1 "F.Mask" user)
		(3 "B.Mask" user)
		(17 "Dwgs.User" user "User.Drawings")
		(19 "Cmts.User" user "User.Comments")
		(21 "Eco1.User" user "User.Eco1")
		(23 "Eco2.User" user "User.Eco2")
		(25 "Edge.Cuts" user)
		(27 "Margin" user)
		(31 "F.CrtYd" user "F.Courtyard")
		(29 "B.CrtYd" user "B.Courtyard")
		(35 "F.Fab" user)
		(33 "B.Fab" user)
	)
	(footprint "antmicro-footprints:R_0402_1005Metric"
		(layer "B.Cu")
		(at 123.4 108.81)
		(descr "Resistor SMD 0402")
		(tags "resistor SMD 0402")
		(property "Reference" "R8"
			(at 0.85 0.4 0)
			(layer "B.SilkS")
			(effects
				(font
					(size 0.7 0.7)
					(thickness 0.15)
				)
				(justify right bottom mirror)
			)
		)
		(property "Value" "R_470R_0402"
			(at -1.011843 -1.772047 0)
			(layer "B.Fab")
			(effects
				(font
					(size 0.7 0.7)
					(thickness 0.15)
				)
				(justify right bottom mirror)
			)
		)
		(property "Datasheet" "https://www.bourns.com/docs/product-datasheets/cr.pdf"
			(at 0 0 0)
			(layer "F.Fab")
			(hide yes)
			(effects
				(font
					(size 1.27 1.27)
					(thickness 0.15)
				)
			)
		)
		(property "Author" "Antmicro"
			(at 0 0 0)
			(layer "B.Fab")
			(hide yes)
			(effects
				(font
					(size 1 1)
					(thickness 0.15)
				)
				(justify mirror)
			)
		)
		(property "License" "Apache-2.0"
			(at 0 0 0)
			(layer "B.Fab")
			(hide yes)
			(effects
				(font
					(size 1 1)
					(thickness 0.15)
				)
				(justify mirror)
			)
		)
		(property "MPN" "CR0402-FX-4700GLF"
			(at 0 0 0)
			(layer "B.Fab")
			(hide yes)
			(effects
				(font
					(size 1 1)
					(thickness 0.15)
				)
				(justify mirror)
			)
		)
		(property "Manufacturer" "Bourns"
			(at 0 0 0)
			(layer "B.Fab")
			(hide yes)
			(effects
				(font
					(size 1 1)
					(thickness 0.15)
				)
				(justify mirror)
			)
		)
		(property "Public" "False"
			(at 0 0 0)
			(layer "B.Fab")
			(hide yes)
			(effects
				(font
					(size 1 1)
					(thickness 0.15)
				)
				(justify mirror)
			)
		)
		(property "Tolerance" "1%"
			(at 0 0 0)
			(layer "B.Fab")
			(hide yes)
			(effects
				(font
					(size 1 1)
					(thickness 0.15)
				)
				(justify mirror)
			)
		)
		(property "Val" "470R"
			(at 0 0 0)
			(layer "B.Fab")
			(hide yes)
			(effects
				(font
					(size 1 1)
					(thickness 0.15)
				)
				(justify mirror)
			)
		)
		(sheetname "2xUSB3.0+RJ45")
		(sheetfile "usb3+rj45.kicad_sch")
		(attr smd)
		(fp_rect
			(start -0.925 0.47)
			(end 0.925 -0.47)
			(stroke
				(width 0.05)
				(type default)
			)
			(fill no)
			(layer "B.CrtYd")
		)
		(fp_rect
			(start -0.5 0.25)
			(end 0.5 -0.25)
			(stroke
				(width 0.15)
				(type solid)
			)
			(fill no)
			(layer "B.Fab")
		)
		(pad "1" smd roundrect
			(at -0.48 0)
			(size 0.59 0.64)
			(layers "B.Cu" "B.Mask" "B.Paste")
			(roundrect_rratio 0.25)
			(net 156 "Net-(J1A-LED_D3)")
			(pintype "passive")
			(teardrops
				(best_length_ratio 0.2)
				(max_length 1)
				(best_width_ratio 0.9)
				(max_width 2)
				(curved_edges yes)
				(filter_ratio 0.9)
				(enabled yes)
				(allow_two_segments yes)
				(prefer_zone_connections yes)
			)
		)
		(pad "2" smd roundrect
			(at 0.48 0)
			(size 0.59 0.64)
			(layers "B.Cu" "B.Mask" "B.Paste")
			(roundrect_rratio 0.25)
			(net 2 "+3V3")
			(pintype "passive")
			(teardrops
				(best_length_ratio 0.2)
				(max_length 1)
				(best_width_ratio 0.9)
				(max_width 2)
				(curved_edges yes)
				(filter_ratio 0.9)
				(enabled yes)
				(allow_two_segments yes)
				(prefer_zone_connections yes)
			)
		)
	)
	(footprint "antmicro-footprints:USON-10_2.5x1mm_P0.5mm"
		(layer "B.Cu")
		(at 314.75 165.71 180)
		(descr "USON-10 2.5x1mm_ Pitch 0.5mm")
		(tags "USON-10 2.5x1mm Pitch 0.5mm")
		(property "Reference" "U15"
			(at 0.85 1.15 90)
			(layer "B.SilkS")
			(effects
				(font
					(size 0.7 0.7)
					(thickness 0.15)
				)
				(justify left bottom mirror)
			)
		)
		(property "Value" "ESD204DQAR"
			(at 0.018 -2.499 0)
			(layer "B.Fab")
			(effects
				(font
					(size 0.7 0.7)
					(thickness 0.15)
				)
				(justify left bottom mirror)
			)
		)
		(property "Datasheet" "https://www.ti.com/lit/ds/symlink/esd204.pdf?ts=1706004844383&ref_url=https%253A%252F%252Fwww.ti.com%252Finterface%252Fdiodes%252Fesd-protection-diodes%252Fproducts.html"
			(at 0 0 180)
			(layer "F.Fab")
			(hide yes)
			(effects
				(font
					(size 1.27 1.27)
					(thickness 0.15)
				)
			)
		)
		(property "Author" "Antmicro"
			(at 625.5 328.62 0)
			(layer "B.Fab")
			(hide yes)
			(effects
				(font
					(size 1 1)
					(thickness 0.15)
				)
				(justify mirror)
			)
		)
		(property "License" "Apache-2.0"
			(at 625.5 328.62 0)
			(layer "B.Fab")
			(hide yes)
			(effects
				(font
					(size 1 1)
					(thickness 0.15)
				)
				(justify mirror)
			)
		)
		(property "MPN" "ESD204DQAR"
			(at 625.5 328.62 0)
			(layer "B.Fab")
			(hide yes)
			(effects
				(font
					(size 1 1)
					(thickness 0.15)
				)
				(justify mirror)
			)
		)
		(property "Manufacturer" "Texas Instruments"
			(at 625.5 328.62 0)
			(layer "B.Fab")
			(hide yes)
			(effects
				(font
					(size 1 1)
					(thickness 0.15)
				)
				(justify mirror)
			)
		)
		(sheetname "Backplane")
		(sheetfile "backplane.kicad_sch")
		(attr smd)
		(fp_line
			(start -0.5 1.401)
			(end 0.498 1.401)
			(stroke
				(width 0.15)
				(type solid)
			)
			(layer "B.SilkS")
		)
		(fp_line
			(start -0.5 -1.398)
			(end 0.498 -1.398)
			(stroke
				(width 0.15)
				(type solid)
			)
			(layer "B.SilkS")
		)
		(fp_circle
			(center -0.68 1.27)
			(end -0.63 1.27)
			(stroke
				(width 0.15)
				(type solid)
			)
			(fill yes)
			(layer "B.SilkS")
		)
		(fp_rect
			(start -0.8 1.5)
			(end 0.8 -1.499)
			(stroke
				(width 0.05)
				(type solid)
			)
			(fill no)
			(layer "B.CrtYd")
		)
		(fp_line
			(start 0.498 -1.249)
			(end 0.498 1.25)
			(stroke
				(width 0.15)
				(type solid)
			)
			(layer "B.Fab")
		)
		(fp_line
			(start 0.498 -1.249)
			(end -0.5 -1.249)
			(stroke
				(width 0.15)
				(type solid)
			)
			(layer "B.Fab")
		)
		(fp_line
			(start -0.25 1.25)
			(end 0.498 1.25)
			(stroke
				(width 0.15)
				(type solid)
			)
			(layer "B.Fab")
		)
		(fp_line
			(start -0.5 1)
			(end -0.25 1.25)
			(stroke
				(width 0.15)
				(type solid)
			)
			(layer "B.Fab")
		)
		(fp_line
			(start -0.5 -1.249)
			(end -0.5 1)
			(stroke
				(width 0.15)
				(type solid)
			)
			(layer "B.Fab")
		)
		(pad "1" smd roundrect
			(at -0.387 1 270)
			(size 0.25 0.55)
			(layers "B.Cu" "B.Mask" "B.Paste")
			(roundrect_rratio 0.25)
			(net 203 "/Backplane/PCIe_{REF}.CK+")
			(pintype "passive")
			(teardrops
				(best_length_ratio 0.2)
				(max_length 1)
				(best_width_ratio 0.9)
				(max_width 2)
				(curved_edges yes)
				(filter_ratio 0.9)
				(enabled yes)
				(allow_two_segments yes)
				(prefer_zone_connections yes)
			)
		)
		(pad "2" smd roundrect
			(at -0.387 0.5 270)
			(size 0.25 0.55)
			(layers "B.Cu" "B.Mask" "B.Paste")
			(roundrect_rratio 0.25)
			(net 205 "/Backplane/PCIe_{REF}.CK-")
			(pintype "passive")
			(teardrops
				(best_length_ratio 0.2)
				(max_length 1)
				(best_width_ratio 0.9)
				(max_width 2)
				(curved_edges yes)
				(filter_ratio 0.9)
				(enabled yes)
				(allow_two_segments yes)
				(prefer_zone_connections yes)
			)
		)
		(pad "3" smd roundrect
			(at -0.387 0 270)
			(size 0.4 0.55)
			(layers "B.Cu" "B.Mask" "B.Paste")
			(roundrect_rratio 0.25)
			(net 1 "GND")
			(pintype "power_in")
			(teardrops
				(best_length_ratio 0.2)
				(max_length 1)
				(best_width_ratio 0.9)
				(max_width 2)
				(curved_edges yes)
				(filter_ratio 0.9)
				(enabled yes)
				(allow_two_segments yes)
				(prefer_zone_connections yes)
			)
		)
		(pad "4" smd roundrect
			(at -0.387 -0.498 270)
			(size 0.25 0.55)
			(layers "B.Cu" "B.Mask" "B.Paste")
			(roundrect_rratio 0.25)
			(net 206 "/Backplane/USB.D+")
			(pintype "passive")
			(teardrops
				(best_length_ratio 0.2)
				(max_length 1)
				(best_width_ratio 0.9)
				(max_width 2)
				(curved_edges yes)
				(filter_ratio 0.9)
				(enabled yes)
				(allow_two_segments yes)
				(prefer_zone_connections yes)
			)
		)
		(pad "5" smd roundrect
			(at -0.387 -0.998 270)
			(size 0.25 0.55)
			(layers "B.Cu" "B.Mask" "B.Paste")
			(roundrect_rratio 0.25)
			(net 204 "/Backplane/USB.D-")
			(pintype "passive")
			(teardrops
				(best_length_ratio 0.2)
				(max_length 1)
				(best_width_ratio 0.9)
				(max_width 2)
				(curved_edges yes)
				(filter_ratio 0.9)
				(enabled yes)
				(allow_two_segments yes)
				(prefer_zone_connections yes)
			)
		)
		(pad "6" smd roundrect
			(at 0.385 -0.998 270)
			(size 0.25 0.55)
			(layers "B.Cu" "B.Mask" "B.Paste")
			(roundrect_rratio 0.25)
			(net 204 "/Backplane/USB.D-")
			(pintype "passive")
			(teardrops
				(best_length_ratio 0.2)
				(max_length 1)
				(best_width_ratio 0.9)
				(max_width 2)
				(curved_edges yes)
				(filter_ratio 0.9)
				(enabled yes)
				(allow_two_segments yes)
				(prefer_zone_connections yes)
			)
		)
		(pad "7" smd roundrect
			(at 0.385 -0.498 270)
			(size 0.25 0.55)
			(layers "B.Cu" "B.Mask" "B.Paste")
			(roundrect_rratio 0.25)
			(net 206 "/Backplane/USB.D+")
			(pintype "passive")
			(teardrops
				(best_length_ratio 0.2)
				(max_length 1)
				(best_width_ratio 0.9)
				(max_width 2)
				(curved_edges yes)
				(filter_ratio 0.9)
				(enabled yes)
				(allow_two_segments yes)
				(prefer_zone_connections yes)
			)
		)
		(pad "8" smd roundrect
			(at 0.385 0 270)
			(size 0.4 0.55)
			(layers "B.Cu" "B.Mask" "B.Paste")
			(roundrect_rratio 0.25)
			(net 1 "GND")
			(pintype "passive")
			(teardrops
				(best_length_ratio 0.2)
				(max_length 1)
				(best_width_ratio 0.9)
				(max_width 2)
				(curved_edges yes)
				(filter_ratio 0.9)
				(enabled yes)
				(allow_two_segments yes)
				(prefer_zone_connections yes)
			)
		)
		(pad "9" smd roundrect
			(at 0.385 0.5 270)
			(size 0.25 0.55)
			(layers "B.Cu" "B.Mask" "B.Paste")
			(roundrect_rratio 0.25)
			(net 205 "/Backplane/PCIe_{REF}.CK-")
			(pintype "passive")
			(teardrops
				(best_length_ratio 0.2)
				(max_length 1)
				(best_width_ratio 0.9)
				(max_width 2)
				(curved_edges yes)
				(filter_ratio 0.9)
				(enabled yes)
				(allow_two_segments yes)
				(prefer_zone_connections yes)
			)
		)
		(pad "10" smd roundrect
			(at 0.385 1 270)
			(size 0.25 0.55)
			(layers "B.Cu" "B.Mask" "B.Paste")
			(roundrect_rratio 0.25)
			(net 203 "/Backplane/PCIe_{REF}.CK+")
			(pintype "passive")
			(teardrops
				(best_length_ratio 0.2)
				(max_length 1)
				(best_width_ratio 0.9)
				(max_width 2)
				(curved_edges yes)
				(filter_ratio 0.9)
				(enabled yes)
				(allow_two_segments yes)
				(prefer_zone_connections yes)
			)
		)
	)
	(footprint "antmicro-footprints:C_0603_1608Metric"
		(layer "B.Cu")
		(at 251.22571 74.06 180)
		(descr "Capacitor SMD 0603")
		(tags "capacitor 0603")
		(property "Reference" "C6"
			(at -0.794998 -1.55 0)
			(layer "B.SilkS")
			(effects
				(font
					(size 0.7 0.7)
					(thickness 0.15)
				)
				(justify left bottom mirror)
			)
		)
		(property "Value" "C_22u_16V_0603"
			(at -1.42757 -1.770288 0)
			(layer "B.Fab")
			(effects
				(font
					(size 0.7 0.7)
					(thickness 0.15)
				)
				(justify left bottom mirror)
			)
		)
		(property "Datasheet" "https://product.samsungsem.com/mlcc/CL10A226MO7JZN.do"
			(at 0 0 180)
			(layer "F.Fab")
			(hide yes)
			(effects
				(font
					(size 1.27 1.27)
					(thickness 0.15)
				)
			)
		)
		(property "Author" "Antmicro"
			(at 502.45142 148.12 0)
			(layer "B.Fab")
			(hide yes)
			(effects
				(font
					(size 1 1)
					(thickness 0.15)
				)
				(justify mirror)
			)
		)
		(property "Dielectric" ""
			(at 502.45142 148.12 0)
			(layer "B.Fab")
			(hide yes)
			(effects
				(font
					(size 1 1)
					(thickness 0.15)
				)
				(justify mirror)
			)
		)
		(property "License" "Apache-2.0"
			(at 502.45142 148.12 0)
			(layer "B.Fab")
			(hide yes)
			(effects
				(font
					(size 1 1)
					(thickness 0.15)
				)
				(justify mirror)
			)
		)
		(property "MPN" "CL10A226MO7JZNC"
			(at 502.45142 148.12 0)
			(layer "B.Fab")
			(hide yes)
			(effects
				(font
					(size 1 1)
					(thickness 0.15)
				)
				(justify mirror)
			)
		)
		(property "Manufacturer" "Samsung Electro-Mechanics"
			(at 502.45142 148.12 0)
			(layer "B.Fab")
			(hide yes)
			(effects
				(font
					(size 1 1)
					(thickness 0.15)
				)
				(justify mirror)
			)
		)
		(property "Public" "False"
			(at 502.45142 148.12 0)
			(layer "B.Fab")
			(hide yes)
			(effects
				(font
					(size 1 1)
					(thickness 0.15)
				)
				(justify mirror)
			)
		)
		(property "Val" "22u"
			(at 502.45142 148.12 0)
			(layer "B.Fab")
			(hide yes)
			(effects
				(font
					(size 1 1)
					(thickness 0.15)
				)
				(justify mirror)
			)
		)
		(property "Voltage" "16V"
			(at 502.45142 148.12 0)
			(layer "B.Fab")
			(hide yes)
			(effects
				(font
					(size 1 1)
					(thickness 0.15)
				)
				(justify mirror)
			)
		)
		(sheetname "Misc")
		(sheetfile "misc.kicad_sch")
		(attr smd)
		(fp_line
			(start 0.15 0.4)
			(end -0.15 0.4)
			(stroke
				(width 0.15)
				(type solid)
			)
			(layer "B.SilkS")
		)
		(fp_line
			(start 0.15 -0.4)
			(end -0.15 -0.4)
			(stroke
				(width 0.15)
				(type solid)
			)
			(layer "B.SilkS")
		)
		(fp_rect
			(start -1.25 0.65)
			(end 1.25 -0.65)
			(stroke
				(width 0.05)
				(type solid)
			)
			(fill no)
			(layer "B.CrtYd")
		)
		(fp_rect
			(start -0.8 0.4)
			(end 0.8 -0.4)
			(stroke
				(width 0.15)
				(type solid)
			)
			(fill no)
			(layer "B.Fab")
		)
		(pad "1" smd roundrect
			(at -0.7 0 180)
			(size 0.8 1)
			(layers "B.Cu" "B.Mask" "B.Paste")
			(roundrect_rratio 0.2)
			(net 1 "GND")
			(pintype "passive")
			(teardrops
				(best_length_ratio 0.2)
				(max_length 1)
				(best_width_ratio 0.9)
				(max_width 2)
				(curved_edges yes)
				(filter_ratio 0.9)
				(enabled yes)
				(allow_two_segments yes)
				(prefer_zone_connections yes)
			)
		)
		(pad "2" smd roundrect
			(at 0.7 0 180)
			(size 0.8 1)
			(layers "B.Cu" "B.Mask" "B.Paste")
			(roundrect_rratio 0.2)
			(net 81 "/Misc/FAN_12V")
			(pintype "passive")
			(teardrops
				(best_length_ratio 0.2)
				(max_length 1)
				(best_width_ratio 0.9)
				(max_width 2)
				(curved_edges yes)
				(filter_ratio 0.9)
				(enabled yes)
				(allow_two_segments yes)
				(prefer_zone_connections yes)
			)
		)
	)
	(footprint "antmicro-footprints:C_0402_1005Metric"
		(layer "B.Cu")
		(at 116.9 90.81)
		(descr "Capacitor SMD 0402")
		(tags "capacitor SMD 0402")
		(property "Reference" "C16"
			(at -1.1 -0.5 0)
			(layer "B.SilkS")
			(effects
				(font
					(size 0.7 0.7)
					(thickness 0.15)
				)
				(justify right bottom mirror)
			)
		)
		(property "Value" "C_100n_0402"
			(at -1.022927 -2.155213 0)
			(layer "B.Fab")
			(effects
				(font
					(size 0.7 0.7)
					(thickness 0.15)
				)
				(justify right bottom mirror)
			)
		)
		(property "Datasheet" "https://www.murata.com/products/productdetail?partno=GRM155R61H104KE14%23"
			(at 0 0 0)
			(layer "F.Fab")
			(hide yes)
			(effects
				(font
					(size 1.27 1.27)
					(thickness 0.15)
				)
			)
		)
		(property "Author" "Antmicro"
			(at 0 0 0)
			(layer "B.Fab")
			(hide yes)
			(effects
				(font
					(size 1 1)
					(thickness 0.15)
				)
				(justify mirror)
			)
		)
		(property "Dielectric" "X5R"
			(at 0 0 0)
			(layer "B.Fab")
			(hide yes)
			(effects
				(font
					(size 1 1)
					(thickness 0.15)
				)
				(justify mirror)
			)
		)
		(property "License" "Apache-2.0"
			(at 0 0 0)
			(layer "B.Fab")
			(hide yes)
			(effects
				(font
					(size 1 1)
					(thickness 0.15)
				)
				(justify mirror)
			)
		)
		(property "MPN" "GRM155R61H104KE14D"
			(at 0 0 0)
			(layer "B.Fab")
			(hide yes)
			(effects
				(font
					(size 1 1)
					(thickness 0.15)
				)
				(justify mirror)
			)
		)
		(property "Manufacturer" "Murata"
			(at 0 0 0)
			(layer "B.Fab")
			(hide yes)
			(effects
				(font
					(size 1 1)
					(thickness 0.15)
				)
				(justify mirror)
			)
		)
		(property "Public" "False"
			(at 0 0 0)
			(layer "B.Fab")
			(hide yes)
			(effects
				(font
					(size 1 1)
					(thickness 0.15)
				)
				(justify mirror)
			)
		)
		(property "Val" "100n"
			(at 0 0 0)
			(layer "B.Fab")
			(hide yes)
			(effects
				(font
					(size 1 1)
					(thickness 0.15)
				)
				(justify mirror)
			)
		)
		(property "Voltage" "50V"
			(at 0 0 0)
			(layer "B.Fab")
			(hide yes)
			(effects
				(font
					(size 1 1)
					(thickness 0.15)
				)
				(justify mirror)
			)
		)
		(sheetname "2xUSB3.0+RJ45")
		(sheetfile "usb3+rj45.kicad_sch")
		(attr smd)
		(fp_rect
			(start -0.925 0.47)
			(end 0.925 -0.47)
			(stroke
				(width 0.05)
				(type default)
			)
			(fill no)
			(layer "B.CrtYd")
		)
		(fp_line
			(start -0.494 -0.248)
			(end 0.504 -0.248)
			(stroke
				(width 0.15)
				(type solid)
			)
			(layer "B.Fab")
		)
		(fp_line
			(start -0.494 0.25)
			(end -0.494 -0.248)
			(stroke
				(width 0.15)
				(type solid)
			)
			(layer "B.Fab")
		)
		(fp_line
			(start 0.504 -0.248)
			(end 0.504 0.25)
			(stroke
				(width 0.15)
				(type solid)
			)
			(layer "B.Fab")
		)
		(fp_line
			(start 0.504 0.25)
			(end -0.494 0.25)
			(stroke
				(width 0.15)
				(type solid)
			)
			(layer "B.Fab")
		)
		(pad "1" smd roundrect
			(at -0.48 0)
			(size 0.59 0.64)
			(layers "B.Cu" "B.Mask" "B.Paste")
			(roundrect_rratio 0.25)
			(net 1 "GND")
			(pintype "passive")
			(teardrops
				(best_length_ratio 0.2)
				(max_length 1)
				(best_width_ratio 0.9)
				(max_width 2)
				(curved_edges yes)
				(filter_ratio 0.9)
				(enabled yes)
				(allow_two_segments yes)
				(prefer_zone_connections yes)
			)
		)
		(pad "2" smd roundrect
			(at 0.48 0)
			(size 0.59 0.64)
			(layers "B.Cu" "B.Mask" "B.Paste")
			(roundrect_rratio 0.25)
			(net 52 "+5V")
			(pintype "passive")
			(teardrops
				(best_length_ratio 0.2)
				(max_length 1)
				(best_width_ratio 0.9)
				(max_width 2)
				(curved_edges yes)
				(filter_ratio 0.9)
				(enabled yes)
				(allow_two_segments yes)
				(prefer_zone_connections yes)
			)
		)
	)
)
